(kicad_pcb
	(version 20260206)
	(generator "pcbnew")
	(generator_version "10.0")
	(general
		(thickness 1.6)
		(legacy_teardrops no)
	)
	(paper "A4")
	(title_block
		(title "03242023_DA0F0TMBIJ0_F0T_Motherboard_J_brd_V01_OCP.brd")
		(comment 1 "Grand Teton / footprints 6069-6076 of 6105")
	)
	(layers
		(0 "F.Cu" signal "TOP")
		(4 "In1.Cu" signal "GND")
		(6 "In2.Cu" signal "IN1")
		(8 "In3.Cu" signal "GND1")
		(10 "In4.Cu" signal "IN2")
		(12 "In5.Cu" signal "GND2")
		(14 "In6.Cu" signal "IN3")
		(16 "In7.Cu" signal "GND3")
		(18 "In8.Cu" signal "VCC")
		(20 "In9.Cu" signal "VCC1")
		(22 "In10.Cu" signal "GND4")
		(24 "In11.Cu" signal "IN4")
		(26 "In12.Cu" signal "GND5")
		(28 "In13.Cu" signal "IN5")
		(30 "In14.Cu" signal "GND6")
		(32 "In15.Cu" signal "IN6")
		(34 "In16.Cu" signal "GND7")
		(2 "B.Cu" signal "BOTTOM")
		(9 "F.Adhes" user "F.Adhesive")
		(11 "B.Adhes" user "B.Adhesive")
		(13 "F.Paste" user "Package Geometry/Pastemask Top")
		(15 "B.Paste" user "Package Geometry/Pastemask Bottom")
		(5 "F.SilkS" user "Ref Des/Silkscreen Top")
		(7 "B.SilkS" user "Ref Des/Silkscreen Bottom")
		(1 "F.Mask" user "Board Geometry/Soldermask Top")
		(3 "B.Mask" user "Board Geometry/Soldermask Bottom")
		(17 "Dwgs.User" user "User.Drawings")
		(19 "Cmts.User" user "User.Comments")
		(21 "Eco1.User" user "User.Eco1")
		(23 "Eco2.User" user "User.Eco2")
		(25 "Edge.Cuts" user "Board Geometry/Outline")
		(27 "Margin" user)
		(31 "F.CrtYd" user "Package Geometry/Place Bound Top")
		(29 "B.CrtYd" user "Package Geometry/Place Bound Bottom")
		(35 "F.Fab" user "Ref Des/Assembly Top")
		(33 "B.Fab" user "Ref Des/Assembly Bottom")
	)
	(footprint ""
		(layer "B.Cu")
		(at 401.832318 -230.94823 90)
		(property "Reference" "R1959"
			(at 0 0 90)
			(layer "B.SilkS")
			(hide yes)
			(effects
				(font
					(size 1.27 1.27)
				)
				(justify mirror)
			)
		)
		(property "Value" ""
			(at 0 0 90)
			(layer "B.Fab")
			(effects
				(font
					(size 1.27 1.27)
				)
				(justify mirror)
			)
		)
		(duplicate_pad_numbers_are_jumpers no)
		(fp_line
			(start 0.7874 -0.4064)
			(end -0.7874 -0.4064)
			(stroke
				(width 0.1524)
				(type default)
			)
			(layer "B.SilkS")
		)
		(fp_line
			(start -0.7874 -0.4064)
			(end -0.7874 0.4064)
			(stroke
				(width 0.1524)
				(type default)
			)
			(layer "B.SilkS")
		)
		(fp_line
			(start 0.7874 0.4064)
			(end 0.7874 -0.4064)
			(stroke
				(width 0.1524)
				(type default)
			)
			(layer "B.SilkS")
		)
		(fp_line
			(start -0.7874 0.4064)
			(end 0.7874 0.4064)
			(stroke
				(width 0.1524)
				(type default)
			)
			(layer "B.SilkS")
		)
		(fp_line
			(start 0.67945 -0.305054)
			(end 0.12065 -0.305054)
			(stroke
				(width 0.1)
				(type default)
			)
			(layer "B.Fab")
		)
		(fp_line
			(start 0.12065 -0.305054)
			(end 0.12065 -0.2794)
			(stroke
				(width 0.1)
				(type default)
			)
			(layer "B.Fab")
		)
		(fp_line
			(start -0.12065 -0.3048)
			(end -0.67945 -0.3048)
			(stroke
				(width 0.1)
				(type default)
			)
			(layer "B.Fab")
		)
		(fp_line
			(start -0.67945 -0.3048)
			(end -0.67945 0.3048)
			(stroke
				(width 0.1)
				(type default)
			)
			(layer "B.Fab")
		)
		(fp_line
			(start 0.12065 -0.2794)
			(end -0.12065 -0.2794)
			(stroke
				(width 0.1)
				(type default)
			)
			(layer "B.Fab")
		)
		(fp_line
			(start -0.12065 -0.2794)
			(end -0.12065 -0.3048)
			(stroke
				(width 0.1)
				(type default)
			)
			(layer "B.Fab")
		)
		(fp_line
			(start 0.12065 0.2794)
			(end 0.12065 0.3048)
			(stroke
				(width 0.1)
				(type default)
			)
			(layer "B.Fab")
		)
		(fp_line
			(start -0.120396 0.2794)
			(end 0.12065 0.2794)
			(stroke
				(width 0.1)
				(type default)
			)
			(layer "B.Fab")
		)
		(fp_line
			(start 0.67945 0.3048)
			(end 0.67945 -0.305054)
			(stroke
				(width 0.1)
				(type default)
			)
			(layer "B.Fab")
		)
		(fp_line
			(start 0.12065 0.3048)
			(end 0.67945 0.3048)
			(stroke
				(width 0.1)
				(type default)
			)
			(layer "B.Fab")
		)
		(fp_line
			(start -0.120396 0.3048)
			(end -0.120396 0.2794)
			(stroke
				(width 0.1)
				(type default)
			)
			(layer "B.Fab")
		)
		(fp_line
			(start -0.67945 0.3048)
			(end -0.120396 0.3048)
			(stroke
				(width 0.1)
				(type default)
			)
			(layer "B.Fab")
		)
		(pad "1" smd circle
			(at 0.40005 0 270)
			(size 0 0)
			(layers "B.Cu" "B.Mask" "B.Paste")
			(net "H_CPU0_PMDOWN_PCH_R2")
		)
		(pad "2" smd circle
			(at -0.40005 0 270)
			(size 0 0)
			(layers "B.Cu" "B.Mask" "B.Paste")
			(net "H_CPU0_PMDOWN_PCH_R")
		)
	)
	(footprint ""
		(layer "B.Cu")
		(at 85.340952 -328.298048 -90)
		(property "Reference" "PC519_P1_6"
			(at 0 0 90)
			(layer "B.SilkS")
			(hide yes)
			(effects
				(font
					(size 1.27 1.27)
				)
				(justify mirror)
			)
		)
		(property "Value" ""
			(at 0 0 90)
			(layer "B.Fab")
			(effects
				(font
					(size 1.27 1.27)
				)
				(justify mirror)
			)
		)
		(duplicate_pad_numbers_are_jumpers no)
		(fp_line
			(start -1.524 0.762)
			(end 1.524 0.762)
			(stroke
				(width 0.1524)
				(type default)
			)
			(layer "B.SilkS")
		)
		(fp_line
			(start 1.524 0.762)
			(end 1.524 -0.762)
			(stroke
				(width 0.1524)
				(type default)
			)
			(layer "B.SilkS")
		)
		(fp_line
			(start -1.524 -0.762)
			(end -1.524 0.762)
			(stroke
				(width 0.1524)
				(type default)
			)
			(layer "B.SilkS")
		)
		(fp_line
			(start 1.524 -0.762)
			(end -1.524 -0.762)
			(stroke
				(width 0.1524)
				(type default)
			)
			(layer "B.SilkS")
		)
		(fp_line
			(start -1.1049 0.724916)
			(end -1.1049 -0.724916)
			(stroke
				(width 0.1)
				(type default)
			)
			(layer "B.Fab")
		)
		(fp_line
			(start 1.1049 0.724916)
			(end -1.1049 0.724916)
			(stroke
				(width 0.1)
				(type default)
			)
			(layer "B.Fab")
		)
		(fp_line
			(start -1.1049 -0.724916)
			(end 1.1049 -0.724916)
			(stroke
				(width 0.1)
				(type default)
			)
			(layer "B.Fab")
		)
		(fp_line
			(start 1.1049 -0.724916)
			(end 1.1049 0.724916)
			(stroke
				(width 0.1)
				(type default)
			)
			(layer "B.Fab")
		)
		(pad "1" smd rect
			(at 0.889 0 270)
			(size 1.016 1.27)
			(layers "B.Cu" "B.Mask" "B.Paste")
			(net "PVCCIN_CPU1")
		)
		(pad "2" smd rect
			(at -0.889 0 270)
			(size 1.016 1.27)
			(layers "B.Cu" "B.Mask" "B.Paste")
			(net "GND")
		)
	)
	(footprint ""
		(layer "B.Cu")
		(at 490.14253 -427.53788 180)
		(property "Reference" "DB6"
			(at 2.845308 -7.762748 270)
			(unlocked yes)
			(layer "B.SilkS")
			(effects
				(font
					(size 0.7874 0.5842)
					(thickness 0.1524)
				)
				(justify left mirror)
			)
		)
		(property "Value" ""
			(at 0 0 0)
			(layer "B.Fab")
			(effects
				(font
					(size 1.27 1.27)
				)
				(justify mirror)
			)
		)
		(duplicate_pad_numbers_are_jumpers no)
		(fp_line
			(start 3.330702 -4.771136)
			(end -3.330702 -4.771136)
			(stroke
				(width 0.1524)
				(type default)
			)
			(layer "B.SilkS")
		)
		(fp_line
			(start 0 4.011168)
			(end 3.330702 -4.771136)
			(stroke
				(width 0.1524)
				(type default)
			)
			(layer "B.SilkS")
		)
		(fp_line
			(start -3.330702 -4.771136)
			(end 0 4.011168)
			(stroke
				(width 0.1524)
				(type default)
			)
			(layer "B.SilkS")
		)
		(fp_line
			(start 3.330702 -4.771136)
			(end -3.330702 -4.771136)
			(stroke
				(width 0.1)
				(type default)
			)
			(layer "B.Fab")
		)
		(fp_line
			(start 0 4.011168)
			(end 3.330702 -4.771136)
			(stroke
				(width 0.1)
				(type default)
			)
			(layer "B.Fab")
		)
		(fp_line
			(start -3.330702 -4.771136)
			(end 0 4.011168)
			(stroke
				(width 0.1)
				(type default)
			)
			(layer "B.Fab")
		)
		(pad "1" thru_hole circle
			(at 0 0)
			(size 2.159 2.159)
			(drill 1.7018)
			(layers "*.Cu" "*.Mask")
			(remove_unused_layers no)
			(net "T1_GND")
			(clearance 0.0254)
			(thermal_gap 0.0254)
		)
		(pad "2" thru_hole circle
			(at 1.27 -3.348736)
			(size 2.159 2.159)
			(drill 1.7018)
			(layers "*.Cu" "*.Mask")
			(remove_unused_layers no)
			(net "TDR_SE_40_OHM_BOT")
			(clearance 0.0254)
			(thermal_gap 0.0254)
		)
		(pad "3" thru_hole circle
			(at -1.27 -3.348736)
			(size 2.159 2.159)
			(drill 1.7018)
			(layers "*.Cu" "*.Mask")
			(remove_unused_layers no)
			(net "TDR_SE_40_OHM_BOT")
			(clearance 0.0254)
			(thermal_gap 0.0254)
		)
	)
	(footprint ""
		(layer "B.Cu")
		(at 164.64788 -121.376948)
		(property "Reference" "R1408"
			(at 0 0 0)
			(layer "B.SilkS")
			(hide yes)
			(effects
				(font
					(size 1.27 1.27)
				)
				(justify mirror)
			)
		)
		(property "Value" ""
			(at 0 0 0)
			(layer "B.Fab")
			(effects
				(font
					(size 1.27 1.27)
				)
				(justify mirror)
			)
		)
		(duplicate_pad_numbers_are_jumpers no)
		(fp_line
			(start -0.7874 -0.4064)
			(end -0.7874 0.4064)
			(stroke
				(width 0.1524)
				(type default)
			)
			(layer "B.SilkS")
		)
		(fp_line
			(start -0.7874 0.4064)
			(end 0.7874 0.4064)
			(stroke
				(width 0.1524)
				(type default)
			)
			(layer "B.SilkS")
		)
		(fp_line
			(start 0.7874 -0.4064)
			(end -0.7874 -0.4064)
			(stroke
				(width 0.1524)
				(type default)
			)
			(layer "B.SilkS")
		)
		(fp_line
			(start 0.7874 0.4064)
			(end 0.7874 -0.4064)
			(stroke
				(width 0.1524)
				(type default)
			)
			(layer "B.SilkS")
		)
		(fp_line
			(start -0.67945 -0.3048)
			(end -0.67945 0.3048)
			(stroke
				(width 0.1)
				(type default)
			)
			(layer "B.Fab")
		)
		(fp_line
			(start -0.67945 0.3048)
			(end -0.120396 0.3048)
			(stroke
				(width 0.1)
				(type default)
			)
			(layer "B.Fab")
		)
		(fp_line
			(start -0.12065 -0.3048)
			(end -0.67945 -0.3048)
			(stroke
				(width 0.1)
				(type default)
			)
			(layer "B.Fab")
		)
		(fp_line
			(start -0.12065 -0.2794)
			(end -0.12065 -0.3048)
			(stroke
				(width 0.1)
				(type default)
			)
			(layer "B.Fab")
		)
		(fp_line
			(start -0.120396 0.2794)
			(end 0.12065 0.2794)
			(stroke
				(width 0.1)
				(type default)
			)
			(layer "B.Fab")
		)
		(fp_line
			(start -0.120396 0.3048)
			(end -0.120396 0.2794)
			(stroke
				(width 0.1)
				(type default)
			)
			(layer "B.Fab")
		)
		(fp_line
			(start 0.12065 -0.305054)
			(end 0.12065 -0.2794)
			(stroke
				(width 0.1)
				(type default)
			)
			(layer "B.Fab")
		)
		(fp_line
			(start 0.12065 -0.2794)
			(end -0.12065 -0.2794)
			(stroke
				(width 0.1)
				(type default)
			)
			(layer "B.Fab")
		)
		(fp_line
			(start 0.12065 0.2794)
			(end 0.12065 0.3048)
			(stroke
				(width 0.1)
				(type default)
			)
			(layer "B.Fab")
		)
		(fp_line
			(start 0.12065 0.3048)
			(end 0.67945 0.3048)
			(stroke
				(width 0.1)
				(type default)
			)
			(layer "B.Fab")
		)
		(fp_line
			(start 0.67945 -0.305054)
			(end 0.12065 -0.305054)
			(stroke
				(width 0.1)
				(type default)
			)
			(layer "B.Fab")
		)
		(fp_line
			(start 0.67945 0.3048)
			(end 0.67945 -0.305054)
			(stroke
				(width 0.1)
				(type default)
			)
			(layer "B.Fab")
		)
		(pad "1" smd circle
			(at 0.40005 0 180)
			(size 0 0)
			(layers "B.Cu" "B.Mask" "B.Paste")
			(net "FM_PVCCINFAON_CPU1_R_EN")
		)
		(pad "2" smd circle
			(at -0.40005 0 180)
			(size 0 0)
			(layers "B.Cu" "B.Mask" "B.Paste")
			(net "GND")
		)
	)
	(footprint ""
		(layer "B.Cu")
		(at 412.611316 -353.25939 -90)
		(property "Reference" "PC615_P0_1"
			(at 0 0 90)
			(layer "B.SilkS")
			(hide yes)
			(effects
				(font
					(size 1.27 1.27)
				)
				(justify mirror)
			)
		)
		(property "Value" ""
			(at 0 0 90)
			(layer "B.Fab")
			(effects
				(font
					(size 1.27 1.27)
				)
				(justify mirror)
			)
		)
		(duplicate_pad_numbers_are_jumpers no)
		(fp_line
			(start -1.524 0.762)
			(end 1.524 0.762)
			(stroke
				(width 0.1524)
				(type default)
			)
			(layer "B.SilkS")
		)
		(fp_line
			(start 1.524 0.762)
			(end 1.524 -0.762)
			(stroke
				(width 0.1524)
				(type default)
			)
			(layer "B.SilkS")
		)
		(fp_line
			(start -1.524 -0.762)
			(end -1.524 0.762)
			(stroke
				(width 0.1524)
				(type default)
			)
			(layer "B.SilkS")
		)
		(fp_line
			(start 1.524 -0.762)
			(end -1.524 -0.762)
			(stroke
				(width 0.1524)
				(type default)
			)
			(layer "B.SilkS")
		)
		(fp_line
			(start -1.1049 0.724916)
			(end -1.1049 -0.724916)
			(stroke
				(width 0.1)
				(type default)
			)
			(layer "B.Fab")
		)
		(fp_line
			(start 1.1049 0.724916)
			(end -1.1049 0.724916)
			(stroke
				(width 0.1)
				(type default)
			)
			(layer "B.Fab")
		)
		(fp_line
			(start -1.1049 -0.724916)
			(end 1.1049 -0.724916)
			(stroke
				(width 0.1)
				(type default)
			)
			(layer "B.Fab")
		)
		(fp_line
			(start 1.1049 -0.724916)
			(end 1.1049 0.724916)
			(stroke
				(width 0.1)
				(type default)
			)
			(layer "B.Fab")
		)
		(pad "1" smd rect
			(at 0.889 0 270)
			(size 1.016 1.27)
			(layers "B.Cu" "B.Mask" "B.Paste")
			(net "PVCCFA_EHV_FIVRA_CPU0")
		)
		(pad "2" smd rect
			(at -0.889 0 270)
			(size 1.016 1.27)
			(layers "B.Cu" "B.Mask" "B.Paste")
			(net "GND")
		)
	)
	(footprint ""
		(layer "B.Cu")
		(at 348.13494 -333.639922 90)
		(property "Reference" "PC305_P0_1"
			(at 0 0 90)
			(layer "B.SilkS")
			(hide yes)
			(effects
				(font
					(size 1.27 1.27)
				)
				(justify mirror)
			)
		)
		(property "Value" ""
			(at 0 0 90)
			(layer "B.Fab")
			(effects
				(font
					(size 1.27 1.27)
				)
				(justify mirror)
			)
		)
		(duplicate_pad_numbers_are_jumpers no)
		(fp_line
			(start 1.524 -0.762)
			(end -1.524 -0.762)
			(stroke
				(width 0.1524)
				(type default)
			)
			(layer "B.SilkS")
		)
		(fp_line
			(start -1.524 -0.762)
			(end -1.524 0.762)
			(stroke
				(width 0.1524)
				(type default)
			)
			(layer "B.SilkS")
		)
		(fp_line
			(start 1.524 0.762)
			(end 1.524 -0.762)
			(stroke
				(width 0.1524)
				(type default)
			)
			(layer "B.SilkS")
		)
		(fp_line
			(start -1.524 0.762)
			(end 1.524 0.762)
			(stroke
				(width 0.1524)
				(type default)
			)
			(layer "B.SilkS")
		)
		(fp_line
			(start 1.1049 -0.724916)
			(end 1.1049 0.724916)
			(stroke
				(width 0.1)
				(type default)
			)
			(layer "B.Fab")
		)
		(fp_line
			(start -1.1049 -0.724916)
			(end 1.1049 -0.724916)
			(stroke
				(width 0.1)
				(type default)
			)
			(layer "B.Fab")
		)
		(fp_line
			(start 1.1049 0.724916)
			(end -1.1049 0.724916)
			(stroke
				(width 0.1)
				(type default)
			)
			(layer "B.Fab")
		)
		(fp_line
			(start -1.1049 0.724916)
			(end -1.1049 -0.724916)
			(stroke
				(width 0.1)
				(type default)
			)
			(layer "B.Fab")
		)
		(pad "1" smd rect
			(at 0.889 0 90)
			(size 1.016 1.27)
			(layers "B.Cu" "B.Mask" "B.Paste")
			(net "SW_P12V_PVCCIN_CPU0_FLT")
		)
		(pad "2" smd rect
			(at -0.889 0 90)
			(size 1.016 1.27)
			(layers "B.Cu" "B.Mask" "B.Paste")
			(net "GND")
		)
	)
	(footprint ""
		(layer "B.Cu")
		(at 123.640342 -366.723168 90)
		(property "Reference" "PC1268"
			(at 0 0 90)
			(layer "B.SilkS")
			(hide yes)
			(effects
				(font
					(size 1.27 1.27)
				)
				(justify mirror)
			)
		)
		(property "Value" ""
			(at 0 0 90)
			(layer "B.Fab")
			(effects
				(font
					(size 1.27 1.27)
				)
				(justify mirror)
			)
		)
		(duplicate_pad_numbers_are_jumpers no)
		(fp_line
			(start 1.524 -0.762)
			(end -1.524 -0.762)
			(stroke
				(width 0.1524)
				(type default)
			)
			(layer "B.SilkS")
		)
		(fp_line
			(start -1.524 -0.762)
			(end -1.524 0.762)
			(stroke
				(width 0.1524)
				(type default)
			)
			(layer "B.SilkS")
		)
		(fp_line
			(start 1.524 0.762)
			(end 1.524 -0.762)
			(stroke
				(width 0.1524)
				(type default)
			)
			(layer "B.SilkS")
		)
		(fp_line
			(start -1.524 0.762)
			(end 1.524 0.762)
			(stroke
				(width 0.1524)
				(type default)
			)
			(layer "B.SilkS")
		)
		(fp_line
			(start 1.1049 -0.724916)
			(end 1.1049 0.724916)
			(stroke
				(width 0.1)
				(type default)
			)
			(layer "B.Fab")
		)
		(fp_line
			(start -1.1049 -0.724916)
			(end 1.1049 -0.724916)
			(stroke
				(width 0.1)
				(type default)
			)
			(layer "B.Fab")
		)
		(fp_line
			(start 1.1049 0.724916)
			(end -1.1049 0.724916)
			(stroke
				(width 0.1)
				(type default)
			)
			(layer "B.Fab")
		)
		(fp_line
			(start -1.1049 0.724916)
			(end -1.1049 -0.724916)
			(stroke
				(width 0.1)
				(type default)
			)
			(layer "B.Fab")
		)
		(pad "1" smd rect
			(at 0.889 0 90)
			(size 1.016 1.27)
			(layers "B.Cu" "B.Mask" "B.Paste")
			(net "PVPP_HBM_CPU1")
		)
		(pad "2" smd rect
			(at -0.889 0 90)
			(size 1.016 1.27)
			(layers "B.Cu" "B.Mask" "B.Paste")
			(net "GND")
		)
	)
	(footprint ""
		(layer "B.Cu")
		(at 137.50798 -22.943058 90)
		(property "Reference" "R4468"
			(at 0 0 90)
			(layer "B.SilkS")
			(hide yes)
			(effects
				(font
					(size 1.27 1.27)
				)
				(justify mirror)
			)
		)
		(property "Value" ""
			(at 0 0 90)
			(layer "B.Fab")
			(effects
				(font
					(size 1.27 1.27)
				)
				(justify mirror)
			)
		)
		(duplicate_pad_numbers_are_jumpers no)
		(fp_line
			(start 0.7874 -0.4064)
			(end -0.7874 -0.4064)
			(stroke
				(width 0.1524)
				(type default)
			)
			(layer "B.SilkS")
		)
		(fp_line
			(start -0.7874 -0.4064)
			(end -0.7874 0.00762)
			(stroke
				(width 0.1524)
				(type default)
			)
			(layer "B.SilkS")
		)
		(fp_line
			(start 0.7874 0.02794)
			(end 0.7874 -0.4064)
			(stroke
				(width 0.1524)
				(type default)
			)
			(layer "B.SilkS")
		)
		(fp_line
			(start -0.41275 0.4064)
			(end 0.44323 0.4064)
			(stroke
				(width 0.1524)
				(type default)
			)
			(layer "B.SilkS")
		)
		(fp_line
			(start 0.67945 -0.305054)
			(end 0.12065 -0.305054)
			(stroke
				(width 0.1)
				(type default)
			)
			(layer "B.Fab")
		)
		(fp_line
			(start 0.12065 -0.305054)
			(end 0.12065 -0.2794)
			(stroke
				(width 0.1)
				(type default)
			)
			(layer "B.Fab")
		)
		(fp_line
			(start -0.12065 -0.3048)
			(end -0.67945 -0.3048)
			(stroke
				(width 0.1)
				(type default)
			)
			(layer "B.Fab")
		)
		(fp_line
			(start -0.67945 -0.3048)
			(end -0.67945 0.3048)
			(stroke
				(width 0.1)
				(type default)
			)
			(layer "B.Fab")
		)
		(fp_line
			(start 0.12065 -0.2794)
			(end -0.12065 -0.2794)
			(stroke
				(width 0.1)
				(type default)
			)
			(layer "B.Fab")
		)
		(fp_line
			(start -0.12065 -0.2794)
			(end -0.12065 -0.3048)
			(stroke
				(width 0.1)
				(type default)
			)
			(layer "B.Fab")
		)
		(fp_line
			(start 0.12065 0.2794)
			(end 0.12065 0.3048)
			(stroke
				(width 0.1)
				(type default)
			)
			(layer "B.Fab")
		)
		(fp_line
			(start -0.120396 0.2794)
			(end 0.12065 0.2794)
			(stroke
				(width 0.1)
				(type default)
			)
			(layer "B.Fab")
		)
		(fp_line
			(start 0.67945 0.3048)
			(end 0.67945 -0.305054)
			(stroke
				(width 0.1)
				(type default)
			)
			(layer "B.Fab")
		)
		(fp_line
			(start 0.12065 0.3048)
			(end 0.67945 0.3048)
			(stroke
				(width 0.1)
				(type default)
			)
			(layer "B.Fab")
		)
		(fp_line
			(start -0.120396 0.3048)
			(end -0.120396 0.2794)
			(stroke
				(width 0.1)
				(type default)
			)
			(layer "B.Fab")
		)
		(fp_line
			(start -0.67945 0.3048)
			(end -0.120396 0.3048)
			(stroke
				(width 0.1)
				(type default)
			)
			(layer "B.Fab")
		)
		(pad "1" smd circle
			(at 0.40005 0 270)
			(size 0 0)
			(layers "B.Cu" "B.Mask" "B.Paste")
			(net "USB2_HUB_2_BUF_EXT_R_DN")
		)
		(pad "2" smd circle
			(at -0.40005 0 270)
			(size 0 0)
			(layers "B.Cu" "B.Mask" "B.Paste")
			(net "USB2_HUB_2_BUF_EXT_DN")
		)
	)
)
